(kicad_pcb
	(version 20260206)
	(generator "pcbnew")
	(generator_version "10.0")
	(general
		(thickness 1.6)
		(legacy_teardrops no)
	)
	(paper "A4")
	(title_block
		(title "timecard-production-celestica-r4006 — R4006-B0001-02_R01.brd")
		(comment 1 "Time Appliance Project (Time Card) / footprints 199-199 of 1113")
	)
	(layers
		(0 "F.Cu" signal "TOP")
		(4 "In1.Cu" signal "L02_GND1")
		(6 "In2.Cu" signal "L03_SIG1")
		(8 "In3.Cu" signal "L04_GND2")
		(10 "In4.Cu" signal "L05_VCC1")
		(12 "In5.Cu" signal "L06_VCC2")
		(14 "In6.Cu" signal "L07_GND3")
		(16 "In7.Cu" signal "L08_SIG2")
		(18 "In8.Cu" signal "L09_GND4")
		(2 "B.Cu" signal "BOTTOM")
		(9 "F.Adhes" user "F.Adhesive")
		(11 "B.Adhes" user "B.Adhesive")
		(13 "F.Paste" user "Package Geometry/Pastemask Top")
		(15 "B.Paste" user "Package Geometry/Pastemask Bottom")
		(5 "F.SilkS" user "Ref Des/Silkscreen Top")
		(7 "B.SilkS" user "Ref Des/Silkscreen Bottom")
		(1 "F.Mask" user "Board Geometry/Soldermask Top")
		(3 "B.Mask" user "Board Geometry/Soldermask Bottom")
		(17 "Dwgs.User" user "User.Drawings")
		(19 "Cmts.User" user "User.Comments")
		(21 "Eco1.User" user "User.Eco1")
		(23 "Eco2.User" user "User.Eco2")
		(25 "Edge.Cuts" user "Board Geometry/Outline")
		(27 "Margin" user)
		(31 "F.CrtYd" user "Package Geometry/Place Bound Top")
		(29 "B.CrtYd" user "Package Geometry/Place Bound Bottom")
		(35 "F.Fab" user "Ref Des/Assembly Top")
		(33 "B.Fab" user "Ref Des/Assembly Bottom")
	)
	(footprint ""
		(layer "F.Cu")
		(at 19.8882 -100.1014)
		(property "Reference" "CR12"
			(at -0.4572 8.19277 0)
			(unlocked yes)
			(layer "F.SilkS")
			(effects
				(font
					(size 0.7874 0.5842)
					(thickness 0.1524)
				)
			)
		)
		(property "Value" ""
			(at 0 0 0)
			(layer "F.Fab")
			(effects
				(font
					(size 1.27 1.27)
				)
			)
		)
		(property "Device Type" "DIODE_3F-G122-10080-01"
			(at -0.1524 8.061706 0)
			(unlocked yes)
			(layer "F.Fab")
			(hide yes)
			(effects
				(font
					(size 0.7874 0.5842)
					(thickness 0.1524)
				)
			)
		)
		(property "User Part Number" "PARTNUM*"
			(at -0.1524 9.052306 0)
			(unlocked yes)
			(layer "Cmts.User")
			(hide yes)
			(effects
				(font
					(size 0.7874 0.5842)
					(thickness 0.1524)
				)
			)
		)
		(duplicate_pad_numbers_are_jumpers no)
		(fp_line
			(start -3.6195 -5.3086)
			(end -3.6195 6.9596)
			(stroke
				(width 0.1)
				(type default)
			)
			(layer "F.SilkS")
		)
		(fp_line
			(start -3.6195 6.9596)
			(end 3.6195 6.9596)
			(stroke
				(width 0.1)
				(type default)
			)
			(layer "F.SilkS")
		)
		(fp_line
			(start 3.6195 -5.3086)
			(end -3.6195 -5.3086)
			(stroke
				(width 0.1)
				(type default)
			)
			(layer "F.SilkS")
		)
		(fp_line
			(start 3.6195 6.9596)
			(end 3.6195 -5.3086)
			(stroke
				(width 0.1)
				(type default)
			)
			(layer "F.SilkS")
		)
		(fp_poly
			(pts
				(xy -2.8956 -5.0546) (xy -1.89992 -5.0546)
				(arc
					(start -1.89992 -4.058158)
					(mid -1.94894 -4.02319)
					(end -1.988312 -3.97764)
				)
				(xy -2.8956 -3.97764)
			)
			(stroke
				(width 0)
				(type default)
			)
			(fill yes)
			(layer "F.Paste")
		)
		(fp_poly
			(pts
				(xy 1.89992 -5.0546) (xy 2.8956 -5.0546) (xy 2.8956 -3.97764)
				(arc
					(start 2.013712 -3.97764)
					(mid 1.963658 -4.032393)
					(end 1.89992 -4.07035)
				)
			)
			(stroke
				(width 0)
				(type default)
			)
			(fill yes)
			(layer "F.Paste")
		)
		(fp_poly
			(pts
				(xy -2.8956 0.06604)
				(arc
					(start -2.014982 0.06604)
					(mid -1.969113 0.141925)
					(end -1.89992 0.197358)
				)
				(xy -1.89992 1.143) (xy -2.8956 1.143)
			)
			(stroke
				(width 0)
				(type default)
			)
			(fill yes)
			(layer "F.Paste")
		)
		(fp_poly
			(pts
				(arc
					(start 1.89992 0.20955)
					(mid 1.984931 0.152263)
					(end 2.040382 0.06604)
				)
				(xy 2.8956 0.06604) (xy 2.8956 1.143) (xy 1.89992 1.143)
			)
			(stroke
				(width 0)
				(type default)
			)
			(fill yes)
			(layer "F.Paste")
		)
		(fp_poly
			(pts
				(xy 0.70104 -5.0546) (xy 1.69672 -5.0546)
				(arc
					(start 1.69672 -4.066032)
					(mid 1.63886 -4.02892)
					(end 1.593088 -3.97764)
				)
				(arc
					(start 0.819912 -3.97764)
					(mid 0.767727 -4.03411)
					(end 0.70104 -4.072382)
				)
			)
			(stroke
				(width 0)
				(type default)
			)
			(fill yes)
			(layer "F.Paste")
		)
		(fp_poly
			(pts
				(xy -2.8956 -2.49428)
				(arc
					(start -2.02184 -2.49428)
					(mid -1.975997 -2.406299)
					(end -1.89992 -2.342642)
				)
				(arc
					(start -1.89992 -1.518158)
					(mid -1.957563 -1.474963)
					(end -2.000758 -1.41732)
				)
				(xy -2.8956 -1.41732)
			)
			(stroke
				(width 0)
				(type default)
			)
			(fill yes)
			(layer "F.Paste")
		)
		(fp_poly
			(pts
				(xy -2.8956 -1.21412)
				(arc
					(start -2.018538 -1.21412)
					(mid -1.97253 -1.132234)
					(end -1.89992 -1.072642)
				)
				(arc
					(start -1.89992 -0.248158)
					(mid -1.961574 -0.20086)
					(end -2.006092 -0.13716)
				)
				(xy -2.8956 -0.13716)
			)
			(stroke
				(width 0)
				(type default)
			)
			(fill yes)
			(layer "F.Paste")
		)
		(fp_poly
			(pts
				(xy -1.69672 -5.0546) (xy -0.70104 -5.0546)
				(arc
					(start -0.70104 -4.060952)
					(mid -0.752971 -4.025129)
					(end -0.794512 -3.97764)
				)
				(arc
					(start -1.567688 -3.97764)
					(mid -1.624144 -4.037369)
					(end -1.69672 -4.075938)
				)
			)
			(stroke
				(width 0)
				(type default)
			)
			(fill yes)
			(layer "F.Paste")
		)
		(fp_poly
			(pts
				(xy -0.49784 -5.0546) (xy 0.49784 -5.0546)
				(arc
					(start 0.49784 -4.063492)
					(mid 0.442948 -4.027013)
					(end 0.399288 -3.97764)
				)
				(arc
					(start -0.373888 -3.97764)
					(mid -0.428212 -4.035727)
					(end -0.49784 -4.07416)
				)
			)
			(stroke
				(width 0)
				(type default)
			)
			(fill yes)
			(layer "F.Paste")
		)
		(fp_poly
			(pts
				(xy -2.8956 -3.77444)
				(arc
					(start -2.024634 -3.77444)
					(mid -1.979299 -3.680405)
					(end -1.89992 -3.612642)
				)
				(arc
					(start -1.89992 -2.788158)
					(mid -1.953372 -2.749058)
					(end -1.994916 -2.69748)
				)
				(xy -2.8956 -2.69748)
			)
			(stroke
				(width 0)
				(type default)
			)
			(fill yes)
			(layer "F.Paste")
		)
		(fp_poly
			(pts
				(arc
					(start -1.69672 0.215138)
					(mid -1.602311 0.157898)
					(end -1.541018 0.06604)
				)
				(arc
					(start -0.821182 0.06604)
					(mid -0.77339 0.144095)
					(end -0.70104 0.200152)
				)
				(xy -0.70104 1.143) (xy -1.69672 1.143)
			)
			(stroke
				(width 0)
				(type default)
			)
			(fill yes)
			(layer "F.Paste")
		)
		(fp_poly
			(pts
				(arc
					(start -0.49784 0.21336)
					(mid -0.406579 0.156025)
					(end -0.347218 0.06604)
				)
				(arc
					(start 0.372618 0.06604)
					(mid 0.422316 0.1462)
					(end 0.49784 0.202692)
				)
				(xy 0.49784 1.143) (xy -0.49784 1.143)
			)
			(stroke
				(width 0)
				(type default)
			)
			(fill yes)
			(layer "F.Paste")
		)
		(fp_poly
			(pts
				(arc
					(start 0.70104 0.211582)
					(mid 0.789213 0.154213)
					(end 0.846582 0.06604)
				)
				(arc
					(start 1.566418 0.06604)
					(mid 1.618046 0.148282)
					(end 1.69672 0.205232)
				)
				(xy 1.69672 1.143) (xy 0.70104 1.143)
			)
			(stroke
				(width 0)
				(type default)
			)
			(fill yes)
			(layer "F.Paste")
		)
		(fp_poly
			(pts
				(arc
					(start 1.89992 -3.60045)
					(mid 1.995752 -3.669513)
					(end 2.050034 -3.77444)
				)
				(xy 2.8956 -3.77444) (xy 2.8956 -2.69748)
				(arc
					(start 2.020316 -2.69748)
					(mid 1.96833 -2.758521)
					(end 1.89992 -2.80035)
				)
			)
			(stroke
				(width 0)
				(type default)
			)
			(fill yes)
			(layer "F.Paste")
		)
		(fp_poly
			(pts
				(arc
					(start 1.89992 -2.33045)
					(mid 1.99227 -2.395559)
					(end 2.04724 -2.49428)
				)
				(xy 2.8956 -2.49428) (xy 2.8956 -1.41732)
				(arc
					(start 2.026158 -1.41732)
					(mid 1.972726 -1.484646)
					(end 1.89992 -1.53035)
				)
			)
			(stroke
				(width 0)
				(type default)
			)
			(fill yes)
			(layer "F.Paste")
		)
		(fp_poly
			(pts
				(arc
					(start 1.89992 -1.06045)
					(mid 1.988656 -1.121624)
					(end 2.043938 -1.21412)
				)
				(xy 2.8956 -1.21412) (xy 2.8956 -0.13716)
				(arc
					(start 2.031492 -0.13716)
					(mid 1.977 -0.210817)
					(end 1.89992 -0.26035)
				)
			)
			(stroke
				(width 0)
				(type default)
			)
			(fill yes)
			(layer "F.Paste")
		)
		(fp_poly
			(pts
				(arc
					(start -0.49784 -3.59664)
					(mid -0.395448 -3.665482)
					(end -0.337566 -3.77444)
				)
				(arc
					(start 0.362966 -3.77444)
					(mid 0.411854 -3.675897)
					(end 0.49784 -3.607308)
				)
				(xy 0.49784 -2.69748) (xy -0.49784 -2.69748)
			)
			(stroke
				(width 0)
				(type default)
			)
			(fill yes)
			(layer "F.Paste")
		)
		(fp_poly
			(pts
				(arc
					(start -1.69672 -2.324862)
					(mid -1.59473 -2.389682)
					(end -1.53416 -2.49428)
				)
				(arc
					(start -0.82804 -2.49428)
					(mid -0.780368 -2.40405)
					(end -0.70104 -2.339848)
				)
				(arc
					(start -0.70104 -1.520952)
					(mid -0.761756 -1.477056)
					(end -0.806958 -1.41732)
				)
				(arc
					(start -1.555242 -1.41732)
					(mid -1.614808 -1.489961)
					(end -1.69672 -1.535938)
				)
			)
			(stroke
				(width 0)
				(type default)
			)
			(fill yes)
			(layer "F.Paste")
		)
		(fp_poly
			(pts
				(arc
					(start -1.69672 -1.054862)
					(mid -1.598466 -1.115866)
					(end -1.537462 -1.21412)
				)
				(arc
					(start -0.824738 -1.21412)
					(mid -0.776855 -1.130025)
					(end -0.70104 -1.069848)
				)
				(arc
					(start -0.70104 -0.250952)
					(mid -0.765815 -0.202999)
					(end -0.812292 -0.13716)
				)
				(arc
					(start -1.549908 -0.13716)
					(mid -1.610415 -0.21627)
					(end -1.69672 -0.265938)
				)
			)
			(stroke
				(width 0)
				(type default)
			)
			(fill yes)
			(layer "F.Paste")
		)
		(fp_poly
			(pts
				(arc
					(start -0.49784 -2.32664)
					(mid -0.399078 -2.391635)
					(end -0.34036 -2.49428)
				)
				(arc
					(start 0.36576 -2.49428)
					(mid 0.415248 -2.401867)
					(end 0.49784 -2.337308)
				)
				(arc
					(start 0.49784 -1.523492)
					(mid 0.434098 -1.479017)
					(end 0.386842 -1.41732)
				)
				(arc
					(start -0.361442 -1.41732)
					(mid -0.418955 -1.48822)
					(end -0.49784 -1.53416)
				)
			)
			(stroke
				(width 0)
				(type default)
			)
			(fill yes)
			(layer "F.Paste")
		)
		(fp_poly
			(pts
				(arc
					(start -0.49784 -1.05664)
					(mid -0.402774 -1.11778)
					(end -0.343662 -1.21412)
				)
				(arc
					(start 0.369062 -1.21412)
					(mid 0.418806 -1.127881)
					(end 0.49784 -1.067308)
				)
				(arc
					(start 0.49784 -0.253492)
					(mid 0.429995 -0.205005)
					(end 0.381508 -0.13716)
				)
				(arc
					(start -0.356108 -0.13716)
					(mid -0.414601 -0.214483)
					(end -0.49784 -0.26416)
				)
			)
			(stroke
				(width 0)
				(type default)
			)
			(fill yes)
			(layer "F.Paste")
		)
		(fp_poly
			(pts
				(arc
					(start 0.70104 -3.598418)
					(mid 0.80016 -3.667446)
					(end 0.856234 -3.77444)
				)
				(arc
					(start 1.556766 -3.77444)
					(mid 1.607449 -3.673697)
					(end 1.69672 -3.604768)
				)
				(arc
					(start 1.69672 -2.796032)
					(mid 1.634297 -2.754934)
					(end 1.586484 -2.69748)
				)
				(arc
					(start 0.826516 -2.69748)
					(mid 0.77244 -2.760286)
					(end 0.70104 -2.802382)
				)
			)
			(stroke
				(width 0)
				(type default)
			)
			(fill yes)
			(layer "F.Paste")
		)
		(fp_poly
			(pts
				(arc
					(start -1.69672 -3.594862)
					(mid -1.591125 -3.663521)
					(end -1.531366 -3.77444)
				)
				(arc
					(start -0.830834 -3.77444)
					(mid -0.783717 -3.678118)
					(end -0.70104 -3.609848)
				)
				(arc
					(start -0.70104 -2.790952)
					(mid -0.757517 -2.751105)
					(end -0.801116 -2.69748)
				)
				(arc
					(start -1.561084 -2.69748)
					(mid -1.619326 -2.763693)
					(end -1.69672 -2.805938)
				)
			)
			(stroke
				(width 0)
				(type default)
			)
			(fill yes)
			(layer "F.Paste")
		)
		(fp_poly
			(pts
				(arc
					(start 0.70104 -2.328418)
					(mid 0.796635 -2.39353)
					(end 0.85344 -2.49428)
				)
				(arc
					(start 1.55956 -2.49428)
					(mid 1.610887 -2.399705)
					(end 1.69672 -2.334768)
				)
				(arc
					(start 1.69672 -1.526032)
					(mid 1.629976 -1.480977)
					(end 1.580642 -1.41732)
				)
				(arc
					(start 0.832358 -1.41732)
					(mid 0.776878 -1.486459)
					(end 0.70104 -1.532382)
				)
			)
			(stroke
				(width 0)
				(type default)
			)
			(fill yes)
			(layer "F.Paste")
		)
		(fp_poly
			(pts
				(arc
					(start 0.70104 -1.058418)
					(mid 0.792979 -1.119634)
					(end 0.850138 -1.21412)
				)
				(arc
					(start 1.562862 -1.21412)
					(mid 1.614405 -1.125644)
					(end 1.69672 -1.064768)
				)
				(arc
					(start 1.69672 -0.256032)
					(mid 1.625778 -0.207052)
					(end 1.575308 -0.13716)
				)
				(arc
					(start 0.837692 -0.13716)
					(mid 0.781193 -0.212676)
					(end 0.70104 -0.262382)
				)
			)
			(stroke
				(width 0)
				(type default)
			)
			(fill yes)
			(layer "F.Paste")
		)
		(fp_rect
			(start -3.8735 7.2136)
			(end 3.8735 -5.5626)
			(stroke
				(width 0)
				(type default)
			)
			(fill no)
			(layer "F.CrtYd")
		)
		(fp_line
			(start -3.3655 -3.1115)
			(end 3.3655 -3.1115)
			(stroke
				(width 0.1)
				(type default)
			)
			(layer "F.Fab")
		)
		(fp_line
			(start -3.3655 3.1115)
			(end -3.3655 -3.1115)
			(stroke
				(width 0.1)
				(type default)
			)
			(layer "F.Fab")
		)
		(fp_line
			(start -2.8575 4.1275)
			(end -2.8575 5.2705)
			(stroke
				(width 0.1)
				(type default)
			)
			(layer "F.Fab")
		)
		(fp_line
			(start -2.8575 5.2705)
			(end -2.7305 5.2705)
			(stroke
				(width 0.1)
				(type default)
			)
			(layer "F.Fab")
		)
		(fp_line
			(start -2.7305 -3.6195)
			(end -2.7305 0.3175)
			(stroke
				(width 0.1)
				(type default)
			)
			(layer "F.Fab")
		)
		(fp_line
			(start -2.7305 0.3175)
			(end 2.7305 0.3175)
			(stroke
				(width 0.1)
				(type default)
			)
			(layer "F.Fab")
		)
		(fp_line
			(start -2.7305 3.1115)
			(end -2.7305 4.1275)
			(stroke
				(width 0.1)
				(type default)
			)
			(layer "F.Fab")
		)
		(fp_line
			(start -2.7305 4.1275)
			(end -2.8575 4.1275)
			(stroke
				(width 0.1)
				(type default)
			)
			(layer "F.Fab")
		)
		(fp_line
			(start -2.7305 5.2705)
			(end -2.7305 6.0325)
			(stroke
				(width 0.1)
				(type default)
			)
			(layer "F.Fab")
		)
		(fp_line
			(start -2.7305 6.0325)
			(end -1.8415 6.0325)
			(stroke
				(width 0.1)
				(type default)
			)
			(layer "F.Fab")
		)
		(fp_line
			(start -1.9685 -4.3815)
			(end -2.7305 -3.6195)
			(stroke
				(width 0.1)
				(type default)
			)
			(layer "F.Fab")
		)
		(fp_line
			(start -1.8415 4.1275)
			(end -1.8415 3.1115)
			(stroke
				(width 0.1)
				(type default)
			)
			(layer "F.Fab")
		)
		(fp_line
			(start -1.8415 5.2705)
			(end -1.7145 5.2705)
			(stroke
				(width 0.1)
				(type default)
			)
			(layer "F.Fab")
		)
		(fp_line
			(start -1.8415 6.0325)
			(end -1.8415 5.2705)
			(stroke
				(width 0.1)
				(type default)
			)
			(layer "F.Fab")
		)
		(fp_line
			(start -1.7145 4.1275)
			(end -1.8415 4.1275)
			(stroke
				(width 0.1)
				(type default)
			)
			(layer "F.Fab")
		)
		(fp_line
			(start -1.7145 5.2705)
			(end -1.7145 4.1275)
			(stroke
				(width 0.1)
				(type default)
			)
			(layer "F.Fab")
		)
		(fp_line
			(start -0.4445 3.1115)
			(end -0.4445 4.1275)
			(stroke
				(width 0.1)
				(type default)
			)
			(layer "F.Fab")
		)
		(fp_line
			(start -0.4445 4.1275)
			(end 0.4445 4.1275)
			(stroke
				(width 0.1)
				(type default)
			)
			(layer "F.Fab")
		)
		(fp_line
			(start 0.4445 4.1275)
			(end 0.4445 3.1115)
			(stroke
				(width 0.1)
				(type default)
			)
			(layer "F.Fab")
		)
		(fp_line
			(start 1.7145 4.1275)
			(end 1.7145 5.2705)
			(stroke
				(width 0.1)
				(type default)
			)
			(layer "F.Fab")
		)
		(fp_line
			(start 1.7145 5.2705)
			(end 1.8415 5.2705)
			(stroke
				(width 0.1)
				(type default)
			)
			(layer "F.Fab")
		)
		(fp_line
			(start 1.8415 3.1115)
			(end 1.8415 4.1275)
			(stroke
				(width 0.1)
				(type default)
			)
			(layer "F.Fab")
		)
		(fp_line
			(start 1.8415 4.1275)
			(end 1.7145 4.1275)
			(stroke
				(width 0.1)
				(type default)
			)
			(layer "F.Fab")
		)
		(fp_line
			(start 1.8415 5.2705)
			(end 1.8415 6.0325)
			(stroke
				(width 0.1)
				(type default)
			)
			(layer "F.Fab")
		)
		(fp_line
			(start 1.8415 6.0325)
			(end 2.7305 6.0325)
			(stroke
				(width 0.1)
				(type default)
			)
			(layer "F.Fab")
		)
		(fp_line
			(start 1.9685 -4.3815)
			(end -1.9685 -4.3815)
			(stroke
				(width 0.1)
				(type default)
			)
			(layer "F.Fab")
		)
		(fp_line
			(start 2.7305 -3.6195)
			(end 1.9685 -4.3815)
			(stroke
				(width 0.1)
				(type default)
			)
			(layer "F.Fab")
		)
		(fp_line
			(start 2.7305 0.3175)
			(end 2.7305 -3.6195)
			(stroke
				(width 0.1)
				(type default)
			)
			(layer "F.Fab")
		)
		(fp_line
			(start 2.7305 4.1275)
			(end 2.7305 3.1115)
			(stroke
				(width 0.1)
				(type default)
			)
			(layer "F.Fab")
		)
		(fp_line
			(start 2.7305 5.2705)
			(end 2.8575 5.2705)
			(stroke
				(width 0.1)
				(type default)
			)
			(layer "F.Fab")
		)
		(fp_line
			(start 2.7305 6.0325)
			(end 2.7305 5.2705)
			(stroke
				(width 0.1)
				(type default)
			)
			(layer "F.Fab")
		)
		(fp_line
			(start 2.8575 4.1275)
			(end 2.7305 4.1275)
			(stroke
				(width 0.1)
				(type default)
			)
			(layer "F.Fab")
		)
		(fp_line
			(start 2.8575 5.2705)
			(end 2.8575 4.1275)
			(stroke
				(width 0.1)
				(type default)
			)
			(layer "F.Fab")
		)
		(fp_line
			(start 3.3655 -3.1115)
			(end 3.3655 3.1115)
			(stroke
				(width 0.1)
				(type default)
			)
			(layer "F.Fab")
		)
		(fp_line
			(start 3.3655 3.1115)
			(end -3.3655 3.1115)
			(stroke
				(width 0.1)
				(type default)
			)
			(layer "F.Fab")
		)
		(fp_text user "1"
			(at -2.6162 8.19277 0)
			(unlocked yes)
			(layer "F.SilkS")
			(effects
				(font
					(size 0.7874 0.5842)
					(thickness 0.1524)
				)
			)
		)
		(fp_text user "3"
			(at -0.1778 -5.95503 0)
			(unlocked yes)
			(layer "F.SilkS")
			(effects
				(font
					(size 0.7874 0.5842)
					(thickness 0.1524)
				)
			)
		)
		(fp_text user "2"
			(at 3.6068 7.68477 0)
			(unlocked yes)
			(layer "F.SilkS")
			(effects
				(font
					(size 0.7874 0.5842)
					(thickness 0.1524)
				)
			)
		)
		(fp_text user "1"
			(at -2.3114 7.65937 0)
			(unlocked yes)
			(layer "F.Fab")
			(effects
				(font
					(size 0.7874 0.5842)
					(thickness 0.1524)
				)
			)
		)
		(fp_text user "3"
			(at -0.1778 -5.95503 0)
			(unlocked yes)
			(layer "F.Fab")
			(effects
				(font
					(size 0.7874 0.5842)
					(thickness 0.1524)
				)
			)
		)
		(fp_text user "2"
			(at 2.3495 7.67207 0)
			(unlocked yes)
			(layer "F.Fab")
			(effects
				(font
					(size 0.7874 0.5842)
					(thickness 0.1524)
				)
			)
		)
		(pad "1" smd rect
			(at -2.286 5.207)
			(size 1.6002 2.9972)
			(layers "F.Cu" "F.Mask" "F.Paste")
			(net "XP12R0V_PCIE")
		)
		(pad "2" smd rect
			(at 2.286 5.207)
			(size 1.6002 2.9972)
			(layers "F.Cu" "F.Mask" "F.Paste")
			(net "XP12R0V_EXT")
		)
		(pad "3" smd rect
			(at 0 -1.9558)
			(size 5.7912 6.1976)
			(layers "F.Cu" "F.Mask" "F.Paste")
			(net "XP12R0V_IN")
		)
	)
)
